# T6G (Grand Teton) — schematic netlist excerpt (pin names and nets, part order shuffled) for the footprints in the layout excerpt that follows; sources: Cadence DE-HDL packaged netlist, KiCad conversion of 04192023_DAF0TMB3IC0_F0TG_MB_C_brd_V02_OCP.brd

PC2143  Q_CAP  10UF 16V 10% X6S  pkg C0805  page 140 : A = P12V_OCP_V3_2 ; B = GND

U28  SN74LVC1G07DBVR  IC  pkg SMLF  page 136
  NC  = NC
  A  = HP_LVC3_OCP_V3_1_P12V_R_PWRGD
  GND  = GND
  Y  = P12V_OCP_V3_1_PLD_R_PWRGD
  VCC  = P3V3_AUX

(kicad_pcb
	(version 20260206)
	(generator "pcbnew")
	(generator_version "10.0")
	(general
		(thickness 1.6)
		(legacy_teardrops no)
	)
	(paper "A4")
	(title_block
		(title "04192023_DAF0TMB3IC0_F0TG_MB_C_brd_V02_OCP.brd")
		(comment 1 "Grand Teton / footprints 3016-3017 of 8354")
	)
	(layers
		(0 "F.Cu" signal "TOP")
		(4 "In1.Cu" signal "GND")
		(6 "In2.Cu" signal "IN1")
		(8 "In3.Cu" signal "GND1")
		(10 "In4.Cu" signal "IN2")
		(12 "In5.Cu" signal "GND2")
		(14 "In6.Cu" signal "IN3")
		(16 "In7.Cu" signal "GND3")
		(18 "In8.Cu" signal "VCC")
		(20 "In9.Cu" signal "VCC1")
		(22 "In10.Cu" signal "GND4")
		(24 "In11.Cu" signal "IN4")
		(26 "In12.Cu" signal "GND5")
		(28 "In13.Cu" signal "IN5")
		(30 "In14.Cu" signal "GND6")
		(32 "In15.Cu" signal "IN6")
		(34 "In16.Cu" signal "GND7")
		(2 "B.Cu" signal "BOTTOM")
		(9 "F.Adhes" user "F.Adhesive")
		(11 "B.Adhes" user "B.Adhesive")
		(13 "F.Paste" user "Package Geometry/Pastemask Top")
		(15 "B.Paste" user "Package Geometry/Pastemask Bottom")
		(5 "F.SilkS" user "Ref Des/Silkscreen Top")
		(7 "B.SilkS" user "Ref Des/Silkscreen Bottom")
		(1 "F.Mask" user "Board Geometry/Soldermask Top")
		(3 "B.Mask" user "Board Geometry/Soldermask Bottom")
		(17 "Dwgs.User" user "User.Drawings")
		(19 "Cmts.User" user "User.Comments")
		(21 "Eco1.User" user "User.Eco1")
		(23 "Eco2.User" user "User.Eco2")
		(25 "Edge.Cuts" user "Board Geometry/Outline")
		(27 "Margin" user)
		(31 "F.CrtYd" user "Package Geometry/Place Bound Top")
		(29 "B.CrtYd" user "Package Geometry/Place Bound Bottom")
		(35 "F.Fab" user "Ref Des/Assembly Top")
		(33 "B.Fab" user "Ref Des/Assembly Bottom")
	)
	(footprint ""
		(layer "F.Cu")
		(at 201.352912 -96.822768)
		(property "Reference" "U28"
			(at -2.032 -2.377948 0)
			(unlocked yes)
			(layer "F.SilkS")
			(effects
				(font
					(size 0.7874 0.5842)
					(thickness 0.1524)
				)
				(justify left)
			)
		)
		(property "Value" ""
			(at 0 0 0)
			(layer "F.Fab")
			(effects
				(font
					(size 1.27 1.27)
				)
			)
		)
		(duplicate_pad_numbers_are_jumpers no)
		(fp_line
			(start -2.0574 -1.651)
			(end -0.381 -1.651)
			(stroke
				(width 0.1524)
				(type default)
			)
			(layer "F.SilkS")
		)
		(fp_line
			(start -2.0574 1.651)
			(end -2.0574 -1.651)
			(stroke
				(width 0.1524)
				(type default)
			)
			(layer "F.SilkS")
		)
		(fp_line
			(start -0.381 -1.651)
			(end 0 -1.016)
			(stroke
				(width 0.1524)
				(type default)
			)
			(layer "F.SilkS")
		)
		(fp_line
			(start 0 -1.016)
			(end 0.381 -1.651)
			(stroke
				(width 0.1524)
				(type default)
			)
			(layer "F.SilkS")
		)
		(fp_line
			(start 0.381 -1.651)
			(end 2.0574 -1.651)
			(stroke
				(width 0.1524)
				(type default)
			)
			(layer "F.SilkS")
		)
		(fp_line
			(start 2.0574 -1.651)
			(end 2.0574 1.651)
			(stroke
				(width 0.1524)
				(type default)
			)
			(layer "F.SilkS")
		)
		(fp_line
			(start 2.0574 1.651)
			(end -2.0574 1.651)
			(stroke
				(width 0.1524)
				(type default)
			)
			(layer "F.SilkS")
		)
		(fp_poly
			(pts
				(xy -2.71272 -0.719328) (xy -2.71272 -1.344168) (xy -2.159 -1.016)
			)
			(stroke
				(width 0)
				(type default)
			)
			(fill yes)
			(layer "F.SilkS")
		)
		(fp_line
			(start -1.599946 -1.199896)
			(end -0.899922 -1.199896)
			(stroke
				(width 0.1)
				(type default)
			)
			(layer "F.Fab")
		)
		(fp_line
			(start -1.599946 1.199896)
			(end -1.599946 -1.199896)
			(stroke
				(width 0.1)
				(type default)
			)
			(layer "F.Fab")
		)
		(fp_line
			(start -0.899922 -1.549908)
			(end 0.899922 -1.549908)
			(stroke
				(width 0.1)
				(type default)
			)
			(layer "F.Fab")
		)
		(fp_line
			(start -0.899922 -1.199896)
			(end -0.899922 -1.549908)
			(stroke
				(width 0.1)
				(type default)
			)
			(layer "F.Fab")
		)
		(fp_line
			(start -0.899922 1.199896)
			(end -1.599946 1.199896)
			(stroke
				(width 0.1)
				(type default)
			)
			(layer "F.Fab")
		)
		(fp_line
			(start -0.899922 1.549908)
			(end -0.899922 1.199896)
			(stroke
				(width 0.1)
				(type default)
			)
			(layer "F.Fab")
		)
		(fp_line
			(start 0.899922 -1.549908)
			(end 0.899922 -1.199896)
			(stroke
				(width 0.1)
				(type default)
			)
			(layer "F.Fab")
		)
		(fp_line
			(start 0.899922 -1.199896)
			(end 1.599946 -1.199896)
			(stroke
				(width 0.1)
				(type default)
			)
			(layer "F.Fab")
		)
		(fp_line
			(start 0.899922 1.199896)
			(end 0.899922 1.549908)
			(stroke
				(width 0.1)
				(type default)
			)
			(layer "F.Fab")
		)
		(fp_line
			(start 0.899922 1.549908)
			(end -0.899922 1.549908)
			(stroke
				(width 0.1)
				(type default)
			)
			(layer "F.Fab")
		)
		(fp_line
			(start 1.599946 -1.199896)
			(end 1.599946 1.199896)
			(stroke
				(width 0.1)
				(type default)
			)
			(layer "F.Fab")
		)
		(fp_line
			(start 1.599946 1.199896)
			(end 0.899922 1.199896)
			(stroke
				(width 0.1)
				(type default)
			)
			(layer "F.Fab")
		)
		(fp_poly
			(pts
				(xy -2.71272 -0.719328) (xy -2.71272 -1.344168) (xy -2.159 -1.016)
			)
			(stroke
				(width 0)
				(type default)
			)
			(fill yes)
			(layer "F.Fab")
		)
		(pad "1" smd rect
			(at -1.225042 -0.94996 270)
			(size 0.5588 1.3462)
			(layers "F.Cu" "F.Mask" "F.Paste")
			(net "Net_10855")
		)
		(pad "2" smd rect
			(at -1.225042 0 270)
			(size 0.5588 1.3462)
			(layers "F.Cu" "F.Mask" "F.Paste")
			(net "HP_LVC3_OCP_V3_1_P12V_R_PWRGD")
		)
		(pad "3" smd rect
			(at -1.225042 0.94996 270)
			(size 0.5588 1.3462)
			(layers "F.Cu" "F.Mask" "F.Paste")
			(net "GND")
		)
		(pad "4" smd rect
			(at 1.225042 0.94996 270)
			(size 0.5588 1.3462)
			(layers "F.Cu" "F.Mask" "F.Paste")
			(net "P12V_OCP_V3_1_PLD_R_PWRGD")
		)
		(pad "5" smd rect
			(at 1.225042 -0.94996 270)
			(size 0.5588 1.3462)
			(layers "F.Cu" "F.Mask" "F.Paste")
			(net "P3V3_AUX")
		)
	)
	(footprint ""
		(layer "F.Cu")
		(at 64.889126 -20.04822 180)
		(property "Reference" "PC2143"
			(at 0 0 180)
			(layer "F.SilkS")
			(hide yes)
			(effects
				(font
					(size 1.27 1.27)
				)
			)
		)
		(property "Value" ""
			(at 0 0 180)
			(layer "F.Fab")
			(effects
				(font
					(size 1.27 1.27)
				)
			)
		)
		(duplicate_pad_numbers_are_jumpers no)
		(fp_line
			(start 1.524 0.762)
			(end -1.524 0.762)
			(stroke
				(width 0.1524)
				(type default)
			)
			(layer "F.SilkS")
		)
		(fp_line
			(start 1.524 -0.762)
			(end 1.524 0.762)
			(stroke
				(width 0.1524)
				(type default)
			)
			(layer "F.SilkS")
		)
		(fp_line
			(start -1.524 0.762)
			(end -1.524 -0.762)
			(stroke
				(width 0.1524)
				(type default)
			)
			(layer "F.SilkS")
		)
		(fp_line
			(start -1.524 -0.762)
			(end 1.524 -0.762)
			(stroke
				(width 0.1524)
				(type default)
			)
			(layer "F.SilkS")
		)
		(fp_line
			(start 1.1049 0.724916)
			(end 1.1049 -0.724916)
			(stroke
				(width 0.1)
				(type default)
			)
			(layer "F.Fab")
		)
		(fp_line
			(start 1.1049 -0.724916)
			(end -1.1049 -0.724916)
			(stroke
				(width 0.1)
				(type default)
			)
			(layer "F.Fab")
		)
		(fp_line
			(start -1.1049 0.724916)
			(end 1.1049 0.724916)
			(stroke
				(width 0.1)
				(type default)
			)
			(layer "F.Fab")
		)
		(fp_line
			(start -1.1049 -0.724916)
			(end -1.1049 0.724916)
			(stroke
				(width 0.1)
				(type default)
			)
			(layer "F.Fab")
		)
		(pad "1" smd rect
			(at -0.889 0)
			(size 1.016 1.27)
			(layers "F.Cu" "F.Mask" "F.Paste")
			(net "P12V_OCP_V3_2")
		)
		(pad "2" smd rect
			(at 0.889 0)
			(size 1.016 1.27)
			(layers "F.Cu" "F.Mask" "F.Paste")
			(net "GND")
		)
	)
)
